# T6G (Grand Teton) — schematic netlist excerpt (pin names and nets, part order shuffled) for the footprints in the layout excerpt that follows; sources: Cadence DE-HDL packaged netlist, KiCad conversion of 04192023_DAF0TMB3IC0_F0TG_MB_C_brd_V02_OCP.brd

R215  Q_RES  33 5% CHIP  pkg 0402LF  page 81 : A = CPU0_PWR_BTN_N ; B = FM_CPU0_PWR_BTN_N
PC6021  Q_CAP  100NF 50V 10% X7R  pkg C0402  page 269 : A = P1V8_AUX ; B = GND

(kicad_pcb
	(version 20260206)
	(generator "pcbnew")
	(generator_version "10.0")
	(general
		(thickness 1.6)
		(legacy_teardrops no)
	)
	(paper "A4")
	(title_block
		(title "04192023_DAF0TMB3IC0_F0TG_MB_C_brd_V02_OCP.brd")
		(comment 1 "Grand Teton / footprints 674-675 of 8354")
	)
	(layers
		(0 "F.Cu" signal "TOP")
		(4 "In1.Cu" signal "GND")
		(6 "In2.Cu" signal "IN1")
		(8 "In3.Cu" signal "GND1")
		(10 "In4.Cu" signal "IN2")
		(12 "In5.Cu" signal "GND2")
		(14 "In6.Cu" signal "IN3")
		(16 "In7.Cu" signal "GND3")
		(18 "In8.Cu" signal "VCC")
		(20 "In9.Cu" signal "VCC1")
		(22 "In10.Cu" signal "GND4")
		(24 "In11.Cu" signal "IN4")
		(26 "In12.Cu" signal "GND5")
		(28 "In13.Cu" signal "IN5")
		(30 "In14.Cu" signal "GND6")
		(32 "In15.Cu" signal "IN6")
		(34 "In16.Cu" signal "GND7")
		(2 "B.Cu" signal "BOTTOM")
		(9 "F.Adhes" user "F.Adhesive")
		(11 "B.Adhes" user "B.Adhesive")
		(13 "F.Paste" user "Package Geometry/Pastemask Top")
		(15 "B.Paste" user "Package Geometry/Pastemask Bottom")
		(5 "F.SilkS" user "Ref Des/Silkscreen Top")
		(7 "B.SilkS" user "Ref Des/Silkscreen Bottom")
		(1 "F.Mask" user "Board Geometry/Soldermask Top")
		(3 "B.Mask" user "Board Geometry/Soldermask Bottom")
		(17 "Dwgs.User" user "User.Drawings")
		(19 "Cmts.User" user "User.Comments")
		(21 "Eco1.User" user "User.Eco1")
		(23 "Eco2.User" user "User.Eco2")
		(25 "Edge.Cuts" user "Board Geometry/Outline")
		(27 "Margin" user)
		(31 "F.CrtYd" user "Package Geometry/Place Bound Top")
		(29 "B.CrtYd" user "Package Geometry/Place Bound Bottom")
		(35 "F.Fab" user "Ref Des/Assembly Top")
		(33 "B.Fab" user "Ref Des/Assembly Bottom")
	)
	(footprint ""
		(layer "F.Cu")
		(at 184.023 -129.377948 -90)
		(property "Reference" "R215"
			(at 0 0 270)
			(layer "F.SilkS")
			(hide yes)
			(effects
				(font
					(size 1.27 1.27)
				)
			)
		)
		(property "Value" ""
			(at 0 0 270)
			(layer "F.Fab")
			(effects
				(font
					(size 1.27 1.27)
				)
			)
		)
		(duplicate_pad_numbers_are_jumpers no)
		(fp_line
			(start -0.7874 0.4064)
			(end -0.7874 -0.4064)
			(stroke
				(width 0.1524)
				(type default)
			)
			(layer "F.SilkS")
		)
		(fp_line
			(start 0.7874 0.4064)
			(end -0.7874 0.4064)
			(stroke
				(width 0.1524)
				(type default)
			)
			(layer "F.SilkS")
		)
		(fp_line
			(start -0.7874 -0.4064)
			(end 0.7874 -0.4064)
			(stroke
				(width 0.1524)
				(type default)
			)
			(layer "F.SilkS")
		)
		(fp_line
			(start 0.7874 -0.4064)
			(end 0.7874 0.4064)
			(stroke
				(width 0.1524)
				(type default)
			)
			(layer "F.SilkS")
		)
		(fp_line
			(start -0.67945 0.3048)
			(end -0.67945 -0.305054)
			(stroke
				(width 0.1)
				(type default)
			)
			(layer "F.Fab")
		)
		(fp_line
			(start -0.12065 0.3048)
			(end -0.67945 0.3048)
			(stroke
				(width 0.1)
				(type default)
			)
			(layer "F.Fab")
		)
		(fp_line
			(start 0.120396 0.3048)
			(end 0.120396 0.2794)
			(stroke
				(width 0.1)
				(type default)
			)
			(layer "F.Fab")
		)
		(fp_line
			(start 0.67945 0.3048)
			(end 0.120396 0.3048)
			(stroke
				(width 0.1)
				(type default)
			)
			(layer "F.Fab")
		)
		(fp_line
			(start -0.12065 0.2794)
			(end -0.12065 0.3048)
			(stroke
				(width 0.1)
				(type default)
			)
			(layer "F.Fab")
		)
		(fp_line
			(start 0.120396 0.2794)
			(end -0.12065 0.2794)
			(stroke
				(width 0.1)
				(type default)
			)
			(layer "F.Fab")
		)
		(fp_line
			(start -0.12065 -0.2794)
			(end 0.12065 -0.2794)
			(stroke
				(width 0.1)
				(type default)
			)
			(layer "F.Fab")
		)
		(fp_line
			(start 0.12065 -0.2794)
			(end 0.12065 -0.3048)
			(stroke
				(width 0.1)
				(type default)
			)
			(layer "F.Fab")
		)
		(fp_line
			(start 0.12065 -0.3048)
			(end 0.67945 -0.3048)
			(stroke
				(width 0.1)
				(type default)
			)
			(layer "F.Fab")
		)
		(fp_line
			(start 0.67945 -0.3048)
			(end 0.67945 0.3048)
			(stroke
				(width 0.1)
				(type default)
			)
			(layer "F.Fab")
		)
		(fp_line
			(start -0.67945 -0.305054)
			(end -0.12065 -0.305054)
			(stroke
				(width 0.1)
				(type default)
			)
			(layer "F.Fab")
		)
		(fp_line
			(start -0.12065 -0.305054)
			(end -0.12065 -0.2794)
			(stroke
				(width 0.1)
				(type default)
			)
			(layer "F.Fab")
		)
		(pad "1" smd circle
			(at -0.40005 0 270)
			(size 0 0)
			(layers "F.Cu" "F.Mask" "F.Paste")
			(net "CPU0_PWR_BTN_N")
		)
		(pad "2" smd circle
			(at 0.40005 0 270)
			(size 0 0)
			(layers "F.Cu" "F.Mask" "F.Paste")
			(net "FM_CPU0_PWR_BTN_N")
		)
	)
	(footprint ""
		(layer "F.Cu")
		(at 152.329642 -73.589134 180)
		(property "Reference" "PC6021"
			(at 0 0 180)
			(layer "F.SilkS")
			(hide yes)
			(effects
				(font
					(size 1.27 1.27)
				)
			)
		)
		(property "Value" ""
			(at 0 0 180)
			(layer "F.Fab")
			(effects
				(font
					(size 1.27 1.27)
				)
			)
		)
		(duplicate_pad_numbers_are_jumpers no)
		(fp_line
			(start 0.7874 0.4064)
			(end -0.7874 0.4064)
			(stroke
				(width 0.1524)
				(type default)
			)
			(layer "F.SilkS")
		)
		(fp_line
			(start 0.7874 -0.4064)
			(end 0.7874 0.4064)
			(stroke
				(width 0.1524)
				(type default)
			)
			(layer "F.SilkS")
		)
		(fp_line
			(start -0.7874 0.4064)
			(end -0.7874 -0.4064)
			(stroke
				(width 0.1524)
				(type default)
			)
			(layer "F.SilkS")
		)
		(fp_line
			(start -0.7874 -0.4064)
			(end 0.7874 -0.4064)
			(stroke
				(width 0.1524)
				(type default)
			)
			(layer "F.SilkS")
		)
		(fp_line
			(start 0.67945 0.3048)
			(end 0.120396 0.3048)
			(stroke
				(width 0.1)
				(type default)
			)
			(layer "F.Fab")
		)
		(fp_line
			(start 0.67945 -0.3048)
			(end 0.67945 0.3048)
			(stroke
				(width 0.1)
				(type default)
			)
			(layer "F.Fab")
		)
		(fp_line
			(start 0.12065 -0.2794)
			(end 0.12065 -0.3048)
			(stroke
				(width 0.1)
				(type default)
			)
			(layer "F.Fab")
		)
		(fp_line
			(start 0.12065 -0.3048)
			(end 0.67945 -0.3048)
			(stroke
				(width 0.1)
				(type default)
			)
			(layer "F.Fab")
		)
		(fp_line
			(start 0.120396 0.3048)
			(end 0.120396 0.2794)
			(stroke
				(width 0.1)
				(type default)
			)
			(layer "F.Fab")
		)
		(fp_line
			(start 0.120396 0.2794)
			(end -0.12065 0.2794)
			(stroke
				(width 0.1)
				(type default)
			)
			(layer "F.Fab")
		)
		(fp_line
			(start -0.12065 0.3048)
			(end -0.67945 0.3048)
			(stroke
				(width 0.1)
				(type default)
			)
			(layer "F.Fab")
		)
		(fp_line
			(start -0.12065 0.2794)
			(end -0.12065 0.3048)
			(stroke
				(width 0.1)
				(type default)
			)
			(layer "F.Fab")
		)
		(fp_line
			(start -0.12065 -0.2794)
			(end 0.12065 -0.2794)
			(stroke
				(width 0.1)
				(type default)
			)
			(layer "F.Fab")
		)
		(fp_line
			(start -0.12065 -0.305054)
			(end -0.12065 -0.2794)
			(stroke
				(width 0.1)
				(type default)
			)
			(layer "F.Fab")
		)
		(fp_line
			(start -0.67945 0.3048)
			(end -0.67945 -0.305054)
			(stroke
				(width 0.1)
				(type default)
			)
			(layer "F.Fab")
		)
		(fp_line
			(start -0.67945 -0.305054)
			(end -0.12065 -0.305054)
			(stroke
				(width 0.1)
				(type default)
			)
			(layer "F.Fab")
		)
		(pad "1" smd circle
			(at -0.40005 0 180)
			(size 0 0)
			(layers "F.Cu" "F.Mask" "F.Paste")
			(net "P1V8_AUX")
		)
		(pad "2" smd circle
			(at 0.40005 0 180)
			(size 0 0)
			(layers "F.Cu" "F.Mask" "F.Paste")
			(net "GND")
		)
	)
)
